# BASEBOARD_FAB2 (Tioga Pass) — schematic netlist excerpt (pin names and nets, part order shuffled) for the footprints in the layout excerpt that follows; sources: Cadence DE-HDL packaged netlist, KiCad conversion of Wiwynn_Tioga_Pass_MB.brd

CT52  CAP_A  0.1UF 16V 10% X7R  pkg 0402V  page 216 : A = VR_PVDDQ_ABC_AIREF2 ; B = GND
R8E16  RES  20.0K 1% CHIP  pkg 0402  page 136 : A = FM_BIOS_TOP_SWAP ; B = GND
C4D4  CAP_A  22.0UF 4V 20% X6S  pkg 0603V  page 203 : A = PVCCIN_CPU0 ; B = GND

(kicad_pcb
	(version 20260206)
	(generator "pcbnew")
	(generator_version "10.0")
	(general
		(thickness 1.6)
		(legacy_teardrops no)
	)
	(paper "A4")
	(title_block
		(title "Wiwynn_Tioga_Pass_MB.brd")
		(comment 1 "Tioga Pass / footprints 1496-1498 of 4770")
	)
	(layers
		(0 "F.Cu" signal "TOP")
		(4 "In1.Cu" signal "L2GND")
		(6 "In2.Cu" signal "L3")
		(8 "In3.Cu" signal "L4GND")
		(10 "In4.Cu" signal "L5")
		(12 "In5.Cu" signal "L6GND")
		(14 "In6.Cu" signal "L7VCC")
		(16 "In7.Cu" signal "L8VCC")
		(18 "In8.Cu" signal "L9GND")
		(20 "In9.Cu" signal "L10")
		(22 "In10.Cu" signal "L11GND")
		(24 "In11.Cu" signal "L12")
		(26 "In12.Cu" signal "L13GND")
		(2 "B.Cu" signal "BOTTOM")
		(9 "F.Adhes" user "F.Adhesive")
		(11 "B.Adhes" user "B.Adhesive")
		(13 "F.Paste" user "Package Geometry/Pastemask Top")
		(15 "B.Paste" user "Package Geometry/Pastemask Bottom")
		(5 "F.SilkS" user "Ref Des/Silkscreen Top")
		(7 "B.SilkS" user "Ref Des/Silkscreen Bottom")
		(1 "F.Mask" user "Board Geometry/Soldermask Top")
		(3 "B.Mask" user "Board Geometry/Soldermask Bottom")
		(17 "Dwgs.User" user "User.Drawings")
		(19 "Cmts.User" user "User.Comments")
		(21 "Eco1.User" user "User.Eco1")
		(23 "Eco2.User" user "User.Eco2")
		(25 "Edge.Cuts" user "Board Geometry/Outline")
		(27 "Margin" user)
		(31 "F.CrtYd" user "Package Geometry/Place Bound Top")
		(29 "B.CrtYd" user "Package Geometry/Place Bound Bottom")
		(35 "F.Fab" user "Ref Des/Assembly Top")
		(33 "B.Fab" user "Ref Des/Assembly Bottom")
	)
	(footprint ""
		(layer "F.Cu")
		(at 417.7919 -58.801 -90)
		(property "Reference" "R8E16"
			(at 0 0 270)
			(layer "F.SilkS")
			(hide yes)
			(effects
				(font
					(size 1.27 1.27)
				)
			)
		)
		(property "Value" ""
			(at 0 0 270)
			(layer "F.Fab")
			(effects
				(font
					(size 1.27 1.27)
				)
			)
		)
		(duplicate_pad_numbers_are_jumpers no)
		(fp_poly
			(pts
				(xy -0.2794 -0.1016) (xy 0.2794 -0.1016) (xy 0.2794 0.9906) (xy -0.2794 0.9906)
			)
			(stroke
				(width 0)
				(type default)
			)
			(fill no)
			(layer "F.CrtYd")
		)
		(fp_line
			(start -0.2794 0.9906)
			(end 0.2794 0.9906)
			(stroke
				(width 0.1)
				(type default)
			)
			(layer "F.Fab")
		)
		(fp_line
			(start 0.2794 0.9906)
			(end 0.2794 -0.1016)
			(stroke
				(width 0.1)
				(type default)
			)
			(layer "F.Fab")
		)
		(fp_line
			(start -0.2794 -0.1016)
			(end -0.2794 0.9906)
			(stroke
				(width 0.1)
				(type default)
			)
			(layer "F.Fab")
		)
		(fp_line
			(start 0.2794 -0.1016)
			(end -0.2794 -0.1016)
			(stroke
				(width 0.1)
				(type default)
			)
			(layer "F.Fab")
		)
		(pad "1" smd rect
			(at 0 0 270)
			(size 0.508 0.508)
			(layers "F.Cu" "F.Mask" "F.Paste")
			(net "FM_BIOS_TOP_SWAP")
		)
		(pad "2" smd rect
			(at 0 0.889 270)
			(size 0.508 0.508)
			(layers "F.Cu" "F.Mask" "F.Paste")
			(net "GND")
		)
		(zone
			(layer "F.Cu")
			(hatch none 0.5)
			(connect_pads
				(clearance 0)
			)
			(min_thickness 0.25)
			(keepout
				(tracks not_allowed)
				(vias allowed)
				(pads allowed)
				(copperpour not_allowed)
				(footprints allowed)
			)
			(placement
				(enabled no)
				(sheetname "")
			)
			(fill
				(thermal_gap 0.5)
				(thermal_bridge_width 0.5)
				(island_removal_mode 0)
			)
			(polygon
				(pts
					(xy 417.1569 -59.055) (xy 417.1569 -58.547) (xy 417.5379 -58.547) (xy 417.5379 -59.055)
				)
			)
		)
		(zone
			(layer "F.Cu")
			(hatch none 0.5)
			(connect_pads
				(clearance 0)
			)
			(min_thickness 0.25)
			(keepout
				(tracks allowed)
				(vias not_allowed)
				(pads allowed)
				(copperpour not_allowed)
				(footprints allowed)
			)
			(placement
				(enabled no)
				(sheetname "")
			)
			(fill
				(thermal_gap 0.5)
				(thermal_bridge_width 0.5)
				(island_removal_mode 0)
			)
			(polygon
				(pts
					(xy 417.5379 -59.055) (xy 417.5379 -58.547) (xy 417.1569 -58.547) (xy 417.1569 -59.055)
				)
			)
		)
	)
	(footprint ""
		(layer "F.Cu")
		(at 351.339658 -1.261364 90)
		(property "Reference" "CT52"
			(at 0.4318 2.74447 90)
			(unlocked yes)
			(layer "F.SilkS")
			(effects
				(font
					(size 0.7874 0.5842)
					(thickness 0.1524)
				)
				(justify left)
			)
		)
		(property "Value" ""
			(at 0 0 90)
			(layer "F.Fab")
			(effects
				(font
					(size 1.27 1.27)
				)
			)
		)
		(duplicate_pad_numbers_are_jumpers no)
		(fp_poly
			(pts
				(xy 0.3048 -0.1016) (xy 0.3048 0.9906) (xy -0.3048 0.9906) (xy -0.3048 -0.1016)
			)
			(stroke
				(width 0)
				(type default)
			)
			(fill no)
			(layer "F.CrtYd")
		)
		(fp_line
			(start 0.3048 -0.1016)
			(end -0.3048 -0.1016)
			(stroke
				(width 0.1)
				(type default)
			)
			(layer "F.Fab")
		)
		(fp_line
			(start -0.3048 -0.1016)
			(end -0.3048 0.9906)
			(stroke
				(width 0.1)
				(type default)
			)
			(layer "F.Fab")
		)
		(fp_line
			(start 0.3048 0.9906)
			(end 0.3048 -0.1016)
			(stroke
				(width 0.1)
				(type default)
			)
			(layer "F.Fab")
		)
		(fp_line
			(start -0.3048 0.9906)
			(end 0.3048 0.9906)
			(stroke
				(width 0.1)
				(type default)
			)
			(layer "F.Fab")
		)
		(pad "1" smd rect
			(at 0 0 90)
			(size 0.508 0.508)
			(layers "F.Cu" "F.Mask" "F.Paste")
			(net "VR_PVDDQ_ABC_AIREF2")
		)
		(pad "2" smd rect
			(at 0 0.889 90)
			(size 0.508 0.508)
			(layers "F.Cu" "F.Mask" "F.Paste")
			(net "GND")
		)
		(zone
			(layer "F.Cu")
			(hatch none 0.5)
			(connect_pads
				(clearance 0)
			)
			(min_thickness 0.25)
			(keepout
				(tracks allowed)
				(vias not_allowed)
				(pads allowed)
				(copperpour not_allowed)
				(footprints allowed)
			)
			(placement
				(enabled no)
				(sheetname "")
			)
			(fill
				(thermal_gap 0.5)
				(thermal_bridge_width 0.5)
				(island_removal_mode 0)
			)
			(polygon
				(pts
					(xy 351.593658 -1.007364) (xy 351.593658 -1.515364) (xy 351.974658 -1.515364) (xy 351.974658 -1.007364)
				)
			)
		)
		(zone
			(layer "F.Cu")
			(hatch none 0.5)
			(connect_pads
				(clearance 0)
			)
			(min_thickness 0.25)
			(keepout
				(tracks not_allowed)
				(vias allowed)
				(pads allowed)
				(copperpour not_allowed)
				(footprints allowed)
			)
			(placement
				(enabled no)
				(sheetname "")
			)
			(fill
				(thermal_gap 0.5)
				(thermal_bridge_width 0.5)
				(island_removal_mode 0)
			)
			(polygon
				(pts
					(xy 351.974658 -1.007364) (xy 351.974658 -1.515364) (xy 351.593658 -1.515364) (xy 351.593658 -1.007364)
				)
			)
		)
	)
	(footprint ""
		(layer "F.Cu")
		(at 214.503 -86.4235)
		(property "Reference" "C4D4"
			(at 0 0 0)
			(layer "F.SilkS")
			(hide yes)
			(effects
				(font
					(size 1.27 1.27)
				)
			)
		)
		(property "Value" ""
			(at 0 0 0)
			(layer "F.Fab")
			(effects
				(font
					(size 1.27 1.27)
				)
			)
		)
		(duplicate_pad_numbers_are_jumpers no)
		(fp_poly
			(pts
				(xy -0.4953 -0.2032) (xy 0.4953 -0.2032) (xy 0.4953 1.6002) (xy -0.4953 1.6002)
			)
			(stroke
				(width 0)
				(type default)
			)
			(fill no)
			(layer "F.CrtYd")
		)
		(fp_line
			(start -0.4953 -0.2032)
			(end 0.4953 -0.2032)
			(stroke
				(width 0.1)
				(type default)
			)
			(layer "F.Fab")
		)
		(fp_line
			(start -0.4953 1.6002)
			(end -0.4953 -0.2032)
			(stroke
				(width 0.1)
				(type default)
			)
			(layer "F.Fab")
		)
		(fp_line
			(start 0.4953 -0.2032)
			(end 0.4953 1.6002)
			(stroke
				(width 0.1)
				(type default)
			)
			(layer "F.Fab")
		)
		(fp_line
			(start 0.4953 1.6002)
			(end -0.4953 1.6002)
			(stroke
				(width 0.1)
				(type default)
			)
			(layer "F.Fab")
		)
		(pad "1" smd rect
			(at 0 0)
			(size 0.762 0.889)
			(layers "F.Cu" "F.Mask" "F.Paste")
			(net "PVCCIN_CPU0")
		)
		(pad "2" smd rect
			(at 0 1.397)
			(size 0.762 0.889)
			(layers "F.Cu" "F.Mask" "F.Paste")
			(net "GND")
		)
		(zone
			(layer "F.Cu")
			(hatch none 0.5)
			(connect_pads
				(clearance 0)
			)
			(min_thickness 0.25)
			(keepout
				(tracks not_allowed)
				(vias allowed)
				(pads allowed)
				(copperpour not_allowed)
				(footprints allowed)
			)
			(placement
				(enabled no)
				(sheetname "")
			)
			(fill
				(thermal_gap 0.5)
				(thermal_bridge_width 0.5)
				(island_removal_mode 0)
			)
			(polygon
				(pts
					(xy 214.122 -85.979) (xy 214.884 -85.979) (xy 214.884 -85.471) (xy 214.122 -85.471)
				)
			)
		)
	)
)
